(kicad_pcb
	(version 20260206)
	(generator "pcbnew")
	(generator_version "10.0")
	(general
		(thickness 1.6)
		(legacy_teardrops no)
	)
	(paper "A4")
	(title_block
		(title "panther-plus-userver — 13130-1b_20150205.brd")
		(comment 1 "Honey Badger (Wiwynn) / footprint 408 of 1509 (U14), pads 122-145 of 145")
	)
	(layers
		(0 "F.Cu" signal "TOP")
		(4 "In1.Cu" signal "L2")
		(6 "In2.Cu" signal "L3")
		(8 "In3.Cu" signal "L4")
		(10 "In4.Cu" signal "L5")
		(12 "In5.Cu" signal "L6")
		(14 "In6.Cu" signal "L7")
		(16 "In7.Cu" signal "L8")
		(18 "In8.Cu" signal "L9")
		(20 "In9.Cu" signal "L10")
		(22 "In10.Cu" signal "L11")
		(2 "B.Cu" signal "BOTTOM")
		(9 "F.Adhes" user "F.Adhesive")
		(11 "B.Adhes" user "B.Adhesive")
		(13 "F.Paste" user "Package Geometry/Pastemask Top")
		(15 "B.Paste" user "Package Geometry/Pastemask Bottom")
		(5 "F.SilkS" user "Ref Des/Silkscreen Top")
		(7 "B.SilkS" user "Ref Des/Silkscreen Bottom")
		(1 "F.Mask" user "Board Geometry/Soldermask Top")
		(3 "B.Mask" user "Board Geometry/Soldermask Bottom")
		(17 "Dwgs.User" user "User.Drawings")
		(19 "Cmts.User" user "User.Comments")
		(21 "Eco1.User" user "User.Eco1")
		(23 "Eco2.User" user "User.Eco2")
		(25 "Edge.Cuts" user "Board Geometry/Outline")
		(27 "Margin" user)
		(31 "F.CrtYd" user "Package Geometry/Place Bound Top")
		(29 "B.CrtYd" user "Package Geometry/Place Bound Bottom")
		(35 "F.Fab" user "Ref Des/Assembly Top")
		(33 "B.Fab" user "Ref Des/Assembly Bottom")
	)
	(footprint ""
		(layer "F.Cu")
		(at 142.748 -34.544)
		(property "Reference" "U14"
			(at 0 0 0)
			(layer "F.SilkS")
			(hide yes)
			(effects
				(font
					(size 1.27 1.27)
				)
			)
		)
		(property "Value" "EP4CE6E22C8N-GP"
			(at 13.9065 9.4361 0)
			(unlocked yes)
			(layer "F.Fab")
			(hide yes)
			(effects
				(font
					(size 1.016 1.016)
					(thickness 0.1524)
				)
			)
		)
		(property "Device Type" "TQFP144-G6H65"
			(at 13.9065 7.9121 0)
			(unlocked yes)
			(layer "F.Fab")
			(hide yes)
			(effects
				(font
					(size 1.016 1.016)
					(thickness 0.1524)
				)
			)
		)
		(duplicate_pad_numbers_are_jumpers no)
		(pad "122" smd rect
			(at 10.6172 2.25044)
			(size 1.27 0.3048)
			(layers "F.Cu" "F.Mask" "F.Paste")
			(net "P3V3_STBY")
		)
		(pad "123" smd rect
			(at 10.6172 1.75006)
			(size 1.27 0.3048)
			(layers "F.Cu" "F.Mask" "F.Paste")
			(net "GND")
		)
		(pad "124" smd rect
			(at 10.6172 1.24968)
			(size 1.27 0.3048)
			(layers "F.Cu" "F.Mask" "F.Paste")
			(net "Net_327")
		)
		(pad "125" smd rect
			(at 10.6172 0.75057)
			(size 1.27 0.3048)
			(layers "F.Cu" "F.Mask" "F.Paste")
			(net "READY_R#")
		)
		(pad "126" smd rect
			(at 10.6172 0.25019)
			(size 1.27 0.3048)
			(layers "F.Cu" "F.Mask" "F.Paste")
			(net "Net_329")
		)
		(pad "127" smd rect
			(at 10.6172 -0.25019)
			(size 1.27 0.3048)
			(layers "F.Cu" "F.Mask" "F.Paste")
			(net "Net_328")
		)
		(pad "128" smd rect
			(at 10.6172 -0.75057)
			(size 1.27 0.3048)
			(layers "F.Cu" "F.Mask" "F.Paste")
			(net "HEARTBEAT_LED")
		)
		(pad "129" smd rect
			(at 10.6172 -1.24968)
			(size 1.27 0.3048)
			(layers "F.Cu" "F.Mask" "F.Paste")
			(net "Net_330")
		)
		(pad "130" smd rect
			(at 10.6172 -1.75006)
			(size 1.27 0.3048)
			(layers "F.Cu" "F.Mask" "F.Paste")
			(net "P3V3_STBY")
		)
		(pad "131" smd rect
			(at 10.6172 -2.25044)
			(size 1.27 0.3048)
			(layers "F.Cu" "F.Mask" "F.Paste")
			(net "GND")
		)
		(pad "132" smd rect
			(at 10.6172 -2.74955)
			(size 1.27 0.3048)
			(layers "F.Cu" "F.Mask" "F.Paste")
			(net "Net_334")
		)
		(pad "133" smd rect
			(at 10.6172 -3.24993)
			(size 1.27 0.3048)
			(layers "F.Cu" "F.Mask" "F.Paste")
			(net "DISABLE")
		)
		(pad "134" smd rect
			(at 10.6172 -3.75031)
			(size 1.27 0.3048)
			(layers "F.Cu" "F.Mask" "F.Paste")
			(net "P1V2_FPGA_D")
		)
		(pad "135" smd rect
			(at 10.6172 -4.24942)
			(size 1.27 0.3048)
			(layers "F.Cu" "F.Mask" "F.Paste")
			(net "PORT80_BIT0")
		)
		(pad "136" smd rect
			(at 10.6172 -4.7498)
			(size 1.27 0.3048)
			(layers "F.Cu" "F.Mask" "F.Paste")
			(net "PORT80_BIT1")
		)
		(pad "137" smd rect
			(at 10.6172 -5.25018)
			(size 1.27 0.3048)
			(layers "F.Cu" "F.Mask" "F.Paste")
			(net "PORT80_BIT2")
		)
		(pad "138" smd rect
			(at 10.6172 -5.75056)
			(size 1.27 0.3048)
			(layers "F.Cu" "F.Mask" "F.Paste")
			(net "PORT80_BIT3")
		)
		(pad "139" smd rect
			(at 10.6172 -6.24967)
			(size 1.27 0.3048)
			(layers "F.Cu" "F.Mask" "F.Paste")
			(net "P3V3_STBY")
		)
		(pad "140" smd rect
			(at 10.6172 -6.75005)
			(size 1.27 0.3048)
			(layers "F.Cu" "F.Mask" "F.Paste")
			(net "GND")
		)
		(pad "141" smd rect
			(at 10.6172 -7.25043)
			(size 1.27 0.3048)
			(layers "F.Cu" "F.Mask" "F.Paste")
			(net "PORT80_BIT4")
		)
		(pad "142" smd rect
			(at 10.6172 -7.74954)
			(size 1.27 0.3048)
			(layers "F.Cu" "F.Mask" "F.Paste")
			(net "PORT80_BIT5")
		)
		(pad "143" smd rect
			(at 10.6172 -8.24992)
			(size 1.27 0.3048)
			(layers "F.Cu" "F.Mask" "F.Paste")
			(net "PORT80_BIT6")
		)
		(pad "144" smd rect
			(at 10.6172 -8.7503)
			(size 1.27 0.3048)
			(layers "F.Cu" "F.Mask" "F.Paste")
			(net "PORT80_BIT7")
		)
		(pad "145" smd rect
			(at 0 0)
			(size 5.9944 5.9944)
			(layers "F.Cu" "F.Mask" "F.Paste")
			(net "GND")
		)
	)
)
